(kicad_pcb
	(version 20260206)
	(generator "pcbnew")
	(generator_version "10.0")
	(general
		(thickness 1.6)
		(legacy_teardrops no)
	)
	(paper "A4")
	(title_block
		(title "Bryce Canyon_IOM_IOC_16318-2_OCP.brd")
		(comment 1 "Bryce Canyon / footprints 1081-1089 of 1605")
	)
	(layers
		(0 "F.Cu" signal "TOP")
		(4 "In1.Cu" signal "L2GND")
		(6 "In2.Cu" signal "L3")
		(8 "In3.Cu" signal "L4VCC")
		(10 "In4.Cu" signal "L5VCC")
		(12 "In5.Cu" signal "L6")
		(14 "In6.Cu" signal "L7GND")
		(2 "B.Cu" signal "BOTTOM")
		(9 "F.Adhes" user "F.Adhesive")
		(11 "B.Adhes" user "B.Adhesive")
		(13 "F.Paste" user "Package Geometry/Pastemask Top")
		(15 "B.Paste" user "Package Geometry/Pastemask Bottom")
		(5 "F.SilkS" user "Ref Des/Silkscreen Top")
		(7 "B.SilkS" user "Ref Des/Silkscreen Bottom")
		(1 "F.Mask" user "Board Geometry/Soldermask Top")
		(3 "B.Mask" user "Board Geometry/Soldermask Bottom")
		(17 "Dwgs.User" user "User.Drawings")
		(19 "Cmts.User" user "User.Comments")
		(21 "Eco1.User" user "User.Eco1")
		(23 "Eco2.User" user "User.Eco2")
		(25 "Edge.Cuts" user "Board Geometry/Outline")
		(27 "Margin" user)
		(31 "F.CrtYd" user "Package Geometry/Place Bound Top")
		(29 "B.CrtYd" user "Package Geometry/Place Bound Bottom")
		(35 "F.Fab" user "Ref Des/Assembly Top")
		(33 "B.Fab" user "Ref Des/Assembly Bottom")
	)
	(footprint ""
		(layer "B.Cu")
		(at 201.177398 -47.807372 -90)
		(property "Reference" "L14"
			(at 0 0 90)
			(layer "B.SilkS")
			(hide yes)
			(effects
				(font
					(size 1.27 1.27)
				)
				(justify mirror)
			)
		)
		(property "Value" "MPZ2012S601AT-GP"
			(at 0 -4.2418 270)
			(unlocked yes)
			(layer "B.Fab")
			(hide yes)
			(effects
				(font
					(size 1.016 1.016)
					(thickness 0.1524)
				)
				(justify mirror)
			)
		)
		(property "Device Type" "L805H42"
			(at 0 -5.7912 270)
			(unlocked yes)
			(layer "B.Fab")
			(hide yes)
			(effects
				(font
					(size 1.016 1.016)
					(thickness 0.1524)
				)
				(justify mirror)
			)
		)
		(duplicate_pad_numbers_are_jumpers no)
		(fp_line
			(start -0.889 1.7018)
			(end 0.889 1.7018)
			(stroke
				(width 0.1524)
				(type default)
			)
			(layer "B.SilkS")
		)
		(fp_line
			(start 0.889 1.7018)
			(end 0.889 -1.7018)
			(stroke
				(width 0.1524)
				(type default)
			)
			(layer "B.SilkS")
		)
		(fp_line
			(start -0.889 -1.7018)
			(end -0.889 1.7018)
			(stroke
				(width 0.1524)
				(type default)
			)
			(layer "B.SilkS")
		)
		(fp_line
			(start 0.889 -1.7018)
			(end -0.889 -1.7018)
			(stroke
				(width 0.1524)
				(type default)
			)
			(layer "B.SilkS")
		)
		(fp_rect
			(start 0.9652 1.778)
			(end -0.9652 -1.778)
			(stroke
				(width 0)
				(type default)
			)
			(fill no)
			(layer "B.CrtYd")
		)
		(fp_rect
			(start 0.9652 1.778)
			(end -0.9652 -1.778)
			(stroke
				(width 0)
				(type default)
			)
			(fill no)
			(layer "B.Fab")
		)
		(pad "1" smd rect
			(at 0 -0.9652 90)
			(size 1.397 1.143)
			(layers "B.Cu" "B.Mask" "B.Paste")
			(net "SYS_PLL_VDD")
		)
		(pad "2" smd rect
			(at 0 0.9652 90)
			(size 1.397 1.143)
			(layers "B.Cu" "B.Mask" "B.Paste")
			(net "P1V8")
		)
	)
	(footprint ""
		(layer "B.Cu")
		(at 189.9412 -66.6369 -90)
		(property "Reference" "C430"
			(at 0 0 90)
			(layer "B.SilkS")
			(hide yes)
			(effects
				(font
					(size 1.27 1.27)
				)
				(justify mirror)
			)
		)
		(property "Value" "SC1KP50V2KX-1GP"
			(at -1.1811 -2.7051 270)
			(unlocked yes)
			(layer "B.Fab")
			(hide yes)
			(effects
				(font
					(size 1.016 1.016)
					(thickness 0.1524)
				)
				(justify mirror)
			)
		)
		(property "Device Type" "C402H22"
			(at -1.1811 -4.2291 270)
			(unlocked yes)
			(layer "B.Fab")
			(hide yes)
			(effects
				(font
					(size 1.016 1.016)
					(thickness 0.1524)
				)
				(justify mirror)
			)
		)
		(duplicate_pad_numbers_are_jumpers no)
		(fp_rect
			(start 0.4318 0.9525)
			(end -0.4318 -0.9525)
			(stroke
				(width 0)
				(type default)
			)
			(fill no)
			(layer "B.CrtYd")
		)
		(fp_rect
			(start 0.4318 0.9525)
			(end -0.4318 -0.9525)
			(stroke
				(width 0)
				(type default)
			)
			(fill no)
			(layer "B.Fab")
		)
		(pad "1" smd custom
			(at 0 -0.4445 90)
			(size 0.1524 0.1524)
			(layers "B.Cu" "B.Mask" "B.Paste")
			(net "P0V975")
			(options
				(clearance outline)
				(anchor circle)
			)
			(primitives
				(gr_poly
					(pts
						(arc
							(start 0.3048 0.2032)
							(mid 0.275042 0.275042)
							(end 0.2032 0.3048)
						)
						(arc
							(start -0.2032 0.3048)
							(mid -0.275042 0.275042)
							(end -0.3048 0.2032)
						)
						(arc
							(start -0.3048 -0.2032)
							(mid -0.275042 -0.275042)
							(end -0.2032 -0.3048)
						)
						(arc
							(start 0.2032 -0.3048)
							(mid 0.275042 -0.275042)
							(end 0.3048 -0.2032)
						)
					)
					(width 0)
					(fill yes)
				)
			)
		)
		(pad "2" smd custom
			(at 0 0.4445 90)
			(size 0.1524 0.1524)
			(layers "B.Cu" "B.Mask" "B.Paste")
			(net "GND")
			(options
				(clearance outline)
				(anchor circle)
			)
			(primitives
				(gr_poly
					(pts
						(arc
							(start 0.3048 0.2032)
							(mid 0.275042 0.275042)
							(end 0.2032 0.3048)
						)
						(arc
							(start -0.2032 0.3048)
							(mid -0.275042 0.275042)
							(end -0.3048 0.2032)
						)
						(arc
							(start -0.3048 -0.2032)
							(mid -0.275042 -0.275042)
							(end -0.2032 -0.3048)
						)
						(arc
							(start 0.2032 -0.3048)
							(mid 0.275042 -0.275042)
							(end 0.3048 -0.2032)
						)
					)
					(width 0)
					(fill yes)
				)
			)
		)
	)
	(footprint ""
		(layer "B.Cu")
		(at 180.213 -78.3336 -90)
		(property "Reference" "TP97"
			(at 0 0 90)
			(layer "B.SilkS")
			(hide yes)
			(effects
				(font
					(size 1.27 1.27)
				)
				(justify mirror)
			)
		)
		(property "Value" "TPAD28-2-GP"
			(at 0.0127 -1.6637 270)
			(unlocked yes)
			(layer "B.Fab")
			(hide yes)
			(effects
				(font
					(size 1.016 1.016)
					(thickness 0.1524)
				)
				(justify mirror)
			)
		)
		(property "Device Type" "TPAD28"
			(at 0.0127 -3.1877 270)
			(unlocked yes)
			(layer "B.Fab")
			(hide yes)
			(effects
				(font
					(size 1.016 1.016)
					(thickness 0.1524)
				)
				(justify mirror)
			)
		)
		(duplicate_pad_numbers_are_jumpers no)
		(fp_poly
			(pts
				(arc
					(start 0 -0.3556)
					(mid 0 0.3556)
					(end 0 -0.3556)
				)
			)
			(stroke
				(width 0)
				(type default)
			)
			(fill no)
			(layer "B.CrtYd")
		)
		(fp_poly
			(pts
				(arc
					(start 0 -0.6096)
					(mid 0 0.6096)
					(end 0 -0.6096)
				)
			)
			(stroke
				(width 0)
				(type default)
			)
			(fill no)
			(layer "B.Fab")
		)
		(pad "1" smd circle
			(at 0 0 90)
			(size 0.7112 0.7112)
			(layers "B.Cu" "B.Mask" "B.Paste")
			(net "IOC_GPIO_12")
		)
	)
	(footprint ""
		(layer "B.Cu")
		(at 201.629518 -81.153 180)
		(property "Reference" "C289"
			(at 0 0 0)
			(layer "B.SilkS")
			(hide yes)
			(effects
				(font
					(size 1.27 1.27)
				)
				(justify mirror)
			)
		)
		(property "Value" "SCD22U10V1KX-GP"
			(at 2.8321 -1.7399 180)
			(unlocked yes)
			(layer "B.Fab")
			(hide yes)
			(effects
				(font
					(size 1.016 1.016)
					(thickness 0.1524)
				)
				(justify mirror)
			)
		)
		(property "Device Type" "C0201H13"
			(at 2.8321 -3.2639 180)
			(unlocked yes)
			(layer "B.Fab")
			(hide yes)
			(effects
				(font
					(size 1.016 1.016)
					(thickness 0.1524)
				)
				(justify mirror)
			)
		)
		(duplicate_pad_numbers_are_jumpers no)
		(fp_rect
			(start 0.2794 0.6477)
			(end -0.2794 -0.6477)
			(stroke
				(width 0)
				(type default)
			)
			(fill no)
			(layer "B.CrtYd")
		)
		(fp_rect
			(start 0.2794 0.6477)
			(end -0.2794 -0.6477)
			(stroke
				(width 0)
				(type default)
			)
			(fill no)
			(layer "B.Fab")
		)
		(pad "1" smd custom
			(at 0 -0.2794)
			(size 0.0762 0.0762)
			(layers "B.Cu" "B.Mask" "B.Paste")
			(net "PCIE_IOM_TO_COMP_8_DP_C")
			(options
				(clearance outline)
				(anchor circle)
			)
			(primitives
				(gr_poly
					(pts
						(arc
							(start 0.1524 0.127)
							(mid 0.137521 0.162921)
							(end 0.1016 0.1778)
						)
						(arc
							(start -0.1016 0.1778)
							(mid -0.137521 0.162921)
							(end -0.1524 0.127)
						)
						(arc
							(start -0.1524 -0.127)
							(mid -0.137521 -0.162921)
							(end -0.1016 -0.1778)
						)
						(arc
							(start 0.1016 -0.1778)
							(mid 0.137521 -0.162921)
							(end 0.1524 -0.127)
						)
					)
					(width 0)
					(fill yes)
				)
			)
		)
		(pad "2" smd custom
			(at 0 0.2794)
			(size 0.0762 0.0762)
			(layers "B.Cu" "B.Mask" "B.Paste")
			(net "PCIE_IOM_TO_COMP_8_DP")
			(options
				(clearance outline)
				(anchor circle)
			)
			(primitives
				(gr_poly
					(pts
						(arc
							(start 0.1524 0.127)
							(mid 0.137521 0.162921)
							(end 0.1016 0.1778)
						)
						(arc
							(start -0.1016 0.1778)
							(mid -0.137521 0.162921)
							(end -0.1524 0.127)
						)
						(arc
							(start -0.1524 -0.127)
							(mid -0.137521 -0.162921)
							(end -0.1016 -0.1778)
						)
						(arc
							(start 0.1016 -0.1778)
							(mid 0.137521 -0.162921)
							(end 0.1524 -0.127)
						)
					)
					(width 0)
					(fill yes)
				)
			)
		)
	)
	(footprint ""
		(layer "B.Cu")
		(at 183.9849 -58.79084 90)
		(property "Reference" "C479"
			(at 0 0 90)
			(layer "B.SilkS")
			(hide yes)
			(effects
				(font
					(size 1.27 1.27)
				)
				(justify mirror)
			)
		)
		(property "Value" "SC1KP50V2KX-1GP"
			(at -1.1811 -2.7051 90)
			(unlocked yes)
			(layer "B.Fab")
			(hide yes)
			(effects
				(font
					(size 1.016 1.016)
					(thickness 0.1524)
				)
				(justify mirror)
			)
		)
		(property "Device Type" "C402H22"
			(at -1.1811 -4.2291 90)
			(unlocked yes)
			(layer "B.Fab")
			(hide yes)
			(effects
				(font
					(size 1.016 1.016)
					(thickness 0.1524)
				)
				(justify mirror)
			)
		)
		(duplicate_pad_numbers_are_jumpers no)
		(fp_rect
			(start 0.4318 0.9525)
			(end -0.4318 -0.9525)
			(stroke
				(width 0)
				(type default)
			)
			(fill no)
			(layer "B.CrtYd")
		)
		(fp_rect
			(start 0.4318 0.9525)
			(end -0.4318 -0.9525)
			(stroke
				(width 0)
				(type default)
			)
			(fill no)
			(layer "B.Fab")
		)
		(pad "1" smd custom
			(at 0 -0.4445 270)
			(size 0.1524 0.1524)
			(layers "B.Cu" "B.Mask" "B.Paste")
			(net "P1V8")
			(options
				(clearance outline)
				(anchor circle)
			)
			(primitives
				(gr_poly
					(pts
						(arc
							(start 0.3048 0.2032)
							(mid 0.275042 0.275042)
							(end 0.2032 0.3048)
						)
						(arc
							(start -0.2032 0.3048)
							(mid -0.275042 0.275042)
							(end -0.3048 0.2032)
						)
						(arc
							(start -0.3048 -0.2032)
							(mid -0.275042 -0.275042)
							(end -0.2032 -0.3048)
						)
						(arc
							(start 0.2032 -0.3048)
							(mid 0.275042 -0.275042)
							(end 0.3048 -0.2032)
						)
					)
					(width 0)
					(fill yes)
				)
			)
		)
		(pad "2" smd custom
			(at 0 0.4445 270)
			(size 0.1524 0.1524)
			(layers "B.Cu" "B.Mask" "B.Paste")
			(net "GND")
			(options
				(clearance outline)
				(anchor circle)
			)
			(primitives
				(gr_poly
					(pts
						(arc
							(start 0.3048 0.2032)
							(mid 0.275042 0.275042)
							(end 0.2032 0.3048)
						)
						(arc
							(start -0.2032 0.3048)
							(mid -0.275042 0.275042)
							(end -0.3048 0.2032)
						)
						(arc
							(start -0.3048 -0.2032)
							(mid -0.275042 -0.275042)
							(end -0.2032 -0.3048)
						)
						(arc
							(start 0.2032 -0.3048)
							(mid 0.275042 -0.275042)
							(end 0.3048 -0.2032)
						)
					)
					(width 0)
					(fill yes)
				)
			)
		)
	)
	(footprint ""
		(layer "B.Cu")
		(at 193.9798 -62.1792 90)
		(property "Reference" "C421"
			(at 0 0 90)
			(layer "B.SilkS")
			(hide yes)
			(effects
				(font
					(size 1.27 1.27)
				)
				(justify mirror)
			)
		)
		(property "Value" "SCD1U6D3V1KX-GP"
			(at 2.8321 -1.7399 90)
			(unlocked yes)
			(layer "B.Fab")
			(hide yes)
			(effects
				(font
					(size 1.016 1.016)
					(thickness 0.1524)
				)
				(justify mirror)
			)
		)
		(property "Device Type" "C0201H13"
			(at 2.8321 -3.2639 90)
			(unlocked yes)
			(layer "B.Fab")
			(hide yes)
			(effects
				(font
					(size 1.016 1.016)
					(thickness 0.1524)
				)
				(justify mirror)
			)
		)
		(duplicate_pad_numbers_are_jumpers no)
		(fp_rect
			(start 0.2794 0.6477)
			(end -0.2794 -0.6477)
			(stroke
				(width 0)
				(type default)
			)
			(fill no)
			(layer "B.CrtYd")
		)
		(fp_rect
			(start 0.2794 0.6477)
			(end -0.2794 -0.6477)
			(stroke
				(width 0)
				(type default)
			)
			(fill no)
			(layer "B.Fab")
		)
		(pad "1" smd custom
			(at 0 -0.2794 270)
			(size 0.0762 0.0762)
			(layers "B.Cu" "B.Mask" "B.Paste")
			(net "P0V975")
			(options
				(clearance outline)
				(anchor circle)
			)
			(primitives
				(gr_poly
					(pts
						(arc
							(start 0.1524 0.127)
							(mid 0.137521 0.162921)
							(end 0.1016 0.1778)
						)
						(arc
							(start -0.1016 0.1778)
							(mid -0.137521 0.162921)
							(end -0.1524 0.127)
						)
						(arc
							(start -0.1524 -0.127)
							(mid -0.137521 -0.162921)
							(end -0.1016 -0.1778)
						)
						(arc
							(start 0.1016 -0.1778)
							(mid 0.137521 -0.162921)
							(end 0.1524 -0.127)
						)
					)
					(width 0)
					(fill yes)
				)
			)
		)
		(pad "2" smd custom
			(at 0 0.2794 270)
			(size 0.0762 0.0762)
			(layers "B.Cu" "B.Mask" "B.Paste")
			(net "GND")
			(options
				(clearance outline)
				(anchor circle)
			)
			(primitives
				(gr_poly
					(pts
						(arc
							(start 0.1524 0.127)
							(mid 0.137521 0.162921)
							(end 0.1016 0.1778)
						)
						(arc
							(start -0.1016 0.1778)
							(mid -0.137521 0.162921)
							(end -0.1524 0.127)
						)
						(arc
							(start -0.1524 -0.127)
							(mid -0.137521 -0.162921)
							(end -0.1016 -0.1778)
						)
						(arc
							(start 0.1016 -0.1778)
							(mid 0.137521 -0.162921)
							(end 0.1524 -0.127)
						)
					)
					(width 0)
					(fill yes)
				)
			)
		)
	)
	(footprint ""
		(layer "B.Cu")
		(at 168.656 -105.029 -90)
		(property "Reference" "C449"
			(at 0 0 90)
			(layer "B.SilkS")
			(hide yes)
			(effects
				(font
					(size 1.27 1.27)
				)
				(justify mirror)
			)
		)
		(property "Value" "SCD1U16V2KX-3GP"
			(at -1.1811 -2.7051 270)
			(unlocked yes)
			(layer "B.Fab")
			(hide yes)
			(effects
				(font
					(size 1.016 1.016)
					(thickness 0.1524)
				)
				(justify mirror)
			)
		)
		(property "Device Type" "C402H22"
			(at -1.1811 -4.2291 270)
			(unlocked yes)
			(layer "B.Fab")
			(hide yes)
			(effects
				(font
					(size 1.016 1.016)
					(thickness 0.1524)
				)
				(justify mirror)
			)
		)
		(duplicate_pad_numbers_are_jumpers no)
		(fp_rect
			(start 0.4318 0.9525)
			(end -0.4318 -0.9525)
			(stroke
				(width 0)
				(type default)
			)
			(fill no)
			(layer "B.CrtYd")
		)
		(fp_rect
			(start 0.4318 0.9525)
			(end -0.4318 -0.9525)
			(stroke
				(width 0)
				(type default)
			)
			(fill no)
			(layer "B.Fab")
		)
		(pad "1" smd custom
			(at 0 -0.4445 90)
			(size 0.1524 0.1524)
			(layers "B.Cu" "B.Mask" "B.Paste")
			(net "P1V8")
			(options
				(clearance outline)
				(anchor circle)
			)
			(primitives
				(gr_poly
					(pts
						(arc
							(start 0.3048 0.2032)
							(mid 0.275042 0.275042)
							(end 0.2032 0.3048)
						)
						(arc
							(start -0.2032 0.3048)
							(mid -0.275042 0.275042)
							(end -0.3048 0.2032)
						)
						(arc
							(start -0.3048 -0.2032)
							(mid -0.275042 -0.275042)
							(end -0.2032 -0.3048)
						)
						(arc
							(start 0.2032 -0.3048)
							(mid 0.275042 -0.275042)
							(end 0.3048 -0.2032)
						)
					)
					(width 0)
					(fill yes)
				)
			)
		)
		(pad "2" smd custom
			(at 0 0.4445 90)
			(size 0.1524 0.1524)
			(layers "B.Cu" "B.Mask" "B.Paste")
			(net "GND")
			(options
				(clearance outline)
				(anchor circle)
			)
			(primitives
				(gr_poly
					(pts
						(arc
							(start 0.3048 0.2032)
							(mid 0.275042 0.275042)
							(end 0.2032 0.3048)
						)
						(arc
							(start -0.2032 0.3048)
							(mid -0.275042 0.275042)
							(end -0.3048 0.2032)
						)
						(arc
							(start -0.3048 -0.2032)
							(mid -0.275042 -0.275042)
							(end -0.2032 -0.3048)
						)
						(arc
							(start 0.2032 -0.3048)
							(mid 0.275042 -0.275042)
							(end 0.3048 -0.2032)
						)
					)
					(width 0)
					(fill yes)
				)
			)
		)
	)
	(footprint ""
		(layer "B.Cu")
		(at 41.0845 -135.89)
		(property "Reference" "TP18"
			(at 0 0 0)
			(layer "B.SilkS")
			(hide yes)
			(effects
				(font
					(size 1.27 1.27)
				)
				(justify mirror)
			)
		)
		(property "Value" "TPAD28-2-GP"
			(at 0.0127 -1.6637 0)
			(unlocked yes)
			(layer "B.Fab")
			(hide yes)
			(effects
				(font
					(size 1.016 1.016)
					(thickness 0.1524)
				)
				(justify mirror)
			)
		)
		(property "Device Type" "TPAD28"
			(at 0.0127 -3.1877 0)
			(unlocked yes)
			(layer "B.Fab")
			(hide yes)
			(effects
				(font
					(size 1.016 1.016)
					(thickness 0.1524)
				)
				(justify mirror)
			)
		)
		(duplicate_pad_numbers_are_jumpers no)
		(fp_poly
			(pts
				(arc
					(start 0.3556 0)
					(mid -0.3556 0)
					(end 0.3556 0)
				)
			)
			(stroke
				(width 0)
				(type default)
			)
			(fill no)
			(layer "B.CrtYd")
		)
		(fp_poly
			(pts
				(arc
					(start 0.6096 0)
					(mid -0.6096 0)
					(end 0.6096 0)
				)
			)
			(stroke
				(width 0)
				(type default)
			)
			(fill no)
			(layer "B.Fab")
		)
		(pad "1" smd circle
			(at 0 0 180)
			(size 0.7112 0.7112)
			(layers "B.Cu" "B.Mask" "B.Paste")
			(net "TP_BMC_GPIOR4")
		)
	)
	(footprint ""
		(layer "B.Cu")
		(at 16.3449 -147.2438 180)
		(property "Reference" "C62"
			(at 0 0 0)
			(layer "B.SilkS")
			(hide yes)
			(effects
				(font
					(size 1.27 1.27)
				)
				(justify mirror)
			)
		)
		(property "Value" "SC1U16V3KX-5GP"
			(at 0 -2.8194 180)
			(unlocked yes)
			(layer "B.Fab")
			(hide yes)
			(effects
				(font
					(size 1.016 1.016)
					(thickness 0.1524)
				)
				(justify mirror)
			)
		)
		(property "Device Type" "C603H36"
			(at 0 -4.3434 180)
			(unlocked yes)
			(layer "B.Fab")
			(hide yes)
			(effects
				(font
					(size 1.016 1.016)
					(thickness 0.1524)
				)
				(justify mirror)
			)
		)
		(duplicate_pad_numbers_are_jumpers no)
		(fp_line
			(start -0.508 0)
			(end 0.508 0)
			(stroke
				(width 0.2032)
				(type default)
			)
			(layer "B.SilkS")
		)
		(fp_rect
			(start 0.5842 1.3335)
			(end -0.5842 -1.3335)
			(stroke
				(width 0)
				(type default)
			)
			(fill no)
			(layer "B.CrtYd")
		)
		(fp_rect
			(start 0.5842 1.3335)
			(end -0.5842 -1.3335)
			(stroke
				(width 0)
				(type default)
			)
			(fill no)
			(layer "B.Fab")
		)
		(pad "1" smd custom
			(at 0 -0.762)
			(size 0.2159 0.2159)
			(layers "B.Cu" "B.Mask" "B.Paste")
			(net "P1V2_STBY")
			(options
				(clearance outline)
				(anchor circle)
			)
			(primitives
				(gr_poly
					(pts
						(arc
							(start -0.3302 0.4318)
							(mid -0.402042 0.402042)
							(end -0.4318 0.3302)
						)
						(arc
							(start -0.4318 -0.3302)
							(mid -0.402042 -0.402042)
							(end -0.3302 -0.4318)
						)
						(arc
							(start 0.3302 -0.4318)
							(mid 0.402042 -0.402042)
							(end 0.4318 -0.3302)
						)
						(arc
							(start 0.4318 0.3302)
							(mid 0.402042 0.402042)
							(end 0.3302 0.4318)
						)
					)
					(width 0)
					(fill yes)
				)
			)
		)
		(pad "2" smd custom
			(at 0 0.762)
			(size 0.2159 0.2159)
			(layers "B.Cu" "B.Mask" "B.Paste")
			(net "GND")
			(options
				(clearance outline)
				(anchor circle)
			)
			(primitives
				(gr_poly
					(pts
						(arc
							(start -0.3302 0.4318)
							(mid -0.402042 0.402042)
							(end -0.4318 0.3302)
						)
						(arc
							(start -0.4318 -0.3302)
							(mid -0.402042 -0.402042)
							(end -0.3302 -0.4318)
						)
						(arc
							(start 0.3302 -0.4318)
							(mid 0.402042 -0.402042)
							(end 0.4318 -0.3302)
						)
						(arc
							(start 0.4318 0.3302)
							(mid 0.402042 0.402042)
							(end 0.3302 0.4318)
						)
					)
					(width 0)
					(fill yes)
				)
			)
		)
	)
)
